(kicad_pcb
	(version 20260206)
	(generator "pcbnew")
	(generator_version "10.0")
	(general
		(thickness 1.6)
		(legacy_teardrops no)
	)
	(paper "A4")
	(title_block
		(title "panther-plus-userver — 13130-1b_20150205.brd")
		(comment 1 "Honey Badger (Wiwynn) / footprints 388-395 of 1509")
	)
	(layers
		(0 "F.Cu" signal "TOP")
		(4 "In1.Cu" signal "L2")
		(6 "In2.Cu" signal "L3")
		(8 "In3.Cu" signal "L4")
		(10 "In4.Cu" signal "L5")
		(12 "In5.Cu" signal "L6")
		(14 "In6.Cu" signal "L7")
		(16 "In7.Cu" signal "L8")
		(18 "In8.Cu" signal "L9")
		(20 "In9.Cu" signal "L10")
		(22 "In10.Cu" signal "L11")
		(2 "B.Cu" signal "BOTTOM")
		(9 "F.Adhes" user "F.Adhesive")
		(11 "B.Adhes" user "B.Adhesive")
		(13 "F.Paste" user "Package Geometry/Pastemask Top")
		(15 "B.Paste" user "Package Geometry/Pastemask Bottom")
		(5 "F.SilkS" user "Ref Des/Silkscreen Top")
		(7 "B.SilkS" user "Ref Des/Silkscreen Bottom")
		(1 "F.Mask" user "Board Geometry/Soldermask Top")
		(3 "B.Mask" user "Board Geometry/Soldermask Bottom")
		(17 "Dwgs.User" user "User.Drawings")
		(19 "Cmts.User" user "User.Comments")
		(21 "Eco1.User" user "User.Eco1")
		(23 "Eco2.User" user "User.Eco2")
		(25 "Edge.Cuts" user "Board Geometry/Outline")
		(27 "Margin" user)
		(31 "F.CrtYd" user "Package Geometry/Place Bound Top")
		(29 "B.CrtYd" user "Package Geometry/Place Bound Bottom")
		(35 "F.Fab" user "Ref Des/Assembly Top")
		(33 "B.Fab" user "Ref Des/Assembly Bottom")
	)
	(footprint ""
		(layer "F.Cu")
		(at 162.052 -54.737 -90)
		(property "Reference" "U17"
			(at 0 0 270)
			(layer "F.SilkS")
			(hide yes)
			(effects
				(font
					(size 1.27 1.27)
				)
			)
		)
		(property "Value" "W25Q64FVZPIG-GP"
			(at -4.3561 -4.9022 270)
			(unlocked yes)
			(layer "F.Fab")
			(hide yes)
			(effects
				(font
					(size 1.016 1.016)
					(thickness 0.1524)
				)
			)
		)
		(property "Device Type" "DFN8A5060-G435345H32"
			(at -4.3561 -6.4262 270)
			(unlocked yes)
			(layer "F.Fab")
			(hide yes)
			(effects
				(font
					(size 1.016 1.016)
					(thickness 0.1524)
				)
			)
		)
		(duplicate_pad_numbers_are_jumpers no)
		(fp_line
			(start -3.0099 4.0132)
			(end -2.2479 4.0132)
			(stroke
				(width 0.1524)
				(type default)
			)
			(layer "F.SilkS")
		)
		(fp_line
			(start 2.2479 4.0132)
			(end 3.0099 4.0132)
			(stroke
				(width 0.1524)
				(type default)
			)
			(layer "F.SilkS")
		)
		(fp_line
			(start 3.0099 4.0132)
			(end 3.0099 3.2512)
			(stroke
				(width 0.1524)
				(type default)
			)
			(layer "F.SilkS")
		)
		(fp_line
			(start -1.905 3.736594)
			(end -1.905 4.244594)
			(stroke
				(width 0.1524)
				(type default)
			)
			(layer "F.SilkS")
		)
		(fp_line
			(start -3.0099 3.2512)
			(end -3.0099 4.0132)
			(stroke
				(width 0.1524)
				(type default)
			)
			(layer "F.SilkS")
		)
		(fp_line
			(start -3.0099 -4.0132)
			(end -3.0099 -3.2512)
			(stroke
				(width 0.1524)
				(type default)
			)
			(layer "F.SilkS")
		)
		(fp_line
			(start -2.2479 -4.0132)
			(end -3.0099 -4.0132)
			(stroke
				(width 0.1524)
				(type default)
			)
			(layer "F.SilkS")
		)
		(fp_poly
			(pts
				(xy 3.0099 -4.0132) (xy 1.9939 -4.0132) (xy 3.0099 -2.9972)
			)
			(stroke
				(width 0)
				(type default)
			)
			(fill yes)
			(layer "F.SilkS")
		)
		(fp_rect
			(start -2.5019 2.9972)
			(end 2.5019 -2.9972)
			(stroke
				(width 0)
				(type default)
			)
			(fill no)
			(layer "F.CrtYd")
		)
		(fp_poly
			(pts
				(xy 3.0099 -2.9972) (xy -2.5019 -2.9972) (xy -2.5019 2.9972) (xy 2.5019 2.9972) (xy 2.5019 -2.9845)
				(xy 3.0099 -2.9845) (xy 3.0099 4.0132) (xy -3.0099 4.0132) (xy -3.0099 -4.0132) (xy 3.0099 -4.0132)
			)
			(stroke
				(width 0)
				(type default)
			)
			(fill no)
			(layer "F.CrtYd")
		)
		(fp_rect
			(start -3.0099 4.0132)
			(end 3.0099 -4.0132)
			(stroke
				(width 0)
				(type default)
			)
			(fill no)
			(layer "F.Fab")
		)
		(pad "1" smd rect
			(at 1.905 -2.822194 270)
			(size 0.635 1.3716)
			(layers "F.Cu" "F.Mask" "F.Paste")
			(net "C_R_CSO#")
		)
		(pad "2" smd rect
			(at 0.635 -2.822194 270)
			(size 0.635 1.3716)
			(layers "F.Cu" "F.Mask" "F.Paste")
			(net "C_R_DATA0")
		)
		(pad "3" smd rect
			(at -0.635 -2.822194 270)
			(size 0.635 1.3716)
			(layers "F.Cu" "F.Mask" "F.Paste")
			(net "P3V3_STBY")
		)
		(pad "4" smd rect
			(at -1.905 -2.822194 270)
			(size 0.635 1.3716)
			(layers "F.Cu" "F.Mask" "F.Paste")
			(net "GND")
		)
		(pad "5" smd rect
			(at -1.905 2.822194 270)
			(size 0.635 1.3716)
			(layers "F.Cu" "F.Mask" "F.Paste")
			(net "C_R_ASDO")
		)
		(pad "6" smd rect
			(at -0.635 2.822194 270)
			(size 0.635 1.3716)
			(layers "F.Cu" "F.Mask" "F.Paste")
			(net "C_R_DCLK")
		)
		(pad "7" smd rect
			(at 0.635 2.822194 270)
			(size 0.635 1.3716)
			(layers "F.Cu" "F.Mask" "F.Paste")
			(net "P3V3_STBY")
		)
		(pad "8" smd rect
			(at 1.905 2.822194 270)
			(size 0.635 1.3716)
			(layers "F.Cu" "F.Mask" "F.Paste")
			(net "P3V3_STBY")
		)
		(pad "9" smd rect
			(at 0 0 270)
			(size 4.3434 3.4544)
			(layers "F.Cu" "F.Mask" "F.Paste")
			(net "GND")
		)
	)
	(footprint ""
		(layer "F.Cu")
		(at 143.891 -19.304)
		(property "Reference" "R97"
			(at 0 0 0)
			(layer "F.SilkS")
			(hide yes)
			(effects
				(font
					(size 1.27 1.27)
				)
			)
		)
		(property "Value" "0R2J-2-GP"
			(at 0.064008 -3.993896 0)
			(unlocked yes)
			(layer "F.Fab")
			(hide yes)
			(effects
				(font
					(size 1.016 1.016)
					(thickness 0.1524)
				)
			)
		)
		(property "Device Type" "R402H16"
			(at 0.064008 -5.517896 0)
			(unlocked yes)
			(layer "F.Fab")
			(hide yes)
			(effects
				(font
					(size 1.016 1.016)
					(thickness 0.1524)
				)
			)
		)
		(duplicate_pad_numbers_are_jumpers no)
		(fp_rect
			(start -0.381 0.8382)
			(end 0.381 -0.8382)
			(stroke
				(width 0)
				(type default)
			)
			(fill no)
			(layer "F.CrtYd")
		)
		(fp_rect
			(start -0.381 0.8382)
			(end 0.381 -0.8382)
			(stroke
				(width 0)
				(type default)
			)
			(fill no)
			(layer "F.Fab")
		)
		(pad "1" smd custom
			(at 0 -0.4318)
			(size 0.127 0.127)
			(layers "F.Cu" "F.Mask" "F.Paste")
			(net "MSEL0")
			(options
				(clearance outline)
				(anchor circle)
			)
			(primitives
				(gr_poly
					(pts
						(arc
							(start -0.2032 -0.2794)
							(mid -0.239121 -0.264521)
							(end -0.254 -0.2286)
						)
						(arc
							(start -0.254 0.2286)
							(mid -0.239121 0.264521)
							(end -0.2032 0.2794)
						)
						(arc
							(start 0.2032 0.2794)
							(mid 0.239121 0.264521)
							(end 0.254 0.2286)
						)
						(arc
							(start 0.254 -0.2286)
							(mid 0.239121 -0.264521)
							(end 0.2032 -0.2794)
						)
					)
					(width 0)
					(fill yes)
				)
			)
		)
		(pad "2" smd custom
			(at 0 0.4318)
			(size 0.127 0.127)
			(layers "F.Cu" "F.Mask" "F.Paste")
			(net "GND")
			(options
				(clearance outline)
				(anchor circle)
			)
			(primitives
				(gr_poly
					(pts
						(arc
							(start -0.2032 -0.2794)
							(mid -0.239121 -0.264521)
							(end -0.254 -0.2286)
						)
						(arc
							(start -0.254 0.2286)
							(mid -0.239121 0.264521)
							(end -0.2032 0.2794)
						)
						(arc
							(start 0.2032 0.2794)
							(mid 0.239121 0.264521)
							(end 0.254 0.2286)
						)
						(arc
							(start 0.254 -0.2286)
							(mid 0.239121 -0.264521)
							(end 0.2032 -0.2794)
						)
					)
					(width 0)
					(fill yes)
				)
			)
		)
	)
	(footprint ""
		(layer "F.Cu")
		(at 167.005 -56.007 180)
		(property "Reference" "C232"
			(at 0 0 180)
			(layer "F.SilkS")
			(hide yes)
			(effects
				(font
					(size 1.27 1.27)
				)
			)
		)
		(property "Value" "SCD1U10V2KX-5GP"
			(at 1.1811 -2.7051 180)
			(unlocked yes)
			(layer "F.Fab")
			(hide yes)
			(effects
				(font
					(size 1.016 1.016)
					(thickness 0.1524)
				)
			)
		)
		(property "Device Type" "C402H22"
			(at 1.1811 -4.2291 180)
			(unlocked yes)
			(layer "F.Fab")
			(hide yes)
			(effects
				(font
					(size 1.016 1.016)
					(thickness 0.1524)
				)
			)
		)
		(duplicate_pad_numbers_are_jumpers no)
		(fp_rect
			(start -0.381 0.7366)
			(end 0.381 -0.7366)
			(stroke
				(width 0)
				(type default)
			)
			(fill no)
			(layer "F.CrtYd")
		)
		(fp_rect
			(start -0.381 0.7366)
			(end 0.381 -0.7366)
			(stroke
				(width 0)
				(type default)
			)
			(fill no)
			(layer "F.Fab")
		)
		(pad "1" smd custom
			(at 0 -0.4572 180)
			(size 0.1143 0.1143)
			(layers "F.Cu" "F.Mask" "F.Paste")
			(net "P3V3_STBY")
			(options
				(clearance outline)
				(anchor circle)
			)
			(primitives
				(gr_poly
					(pts
						(arc
							(start -0.254 -0.1778)
							(mid -0.239121 -0.213721)
							(end -0.2032 -0.2286)
						)
						(arc
							(start 0.2032 -0.2286)
							(mid 0.239121 -0.213721)
							(end 0.254 -0.1778)
						)
						(arc
							(start 0.254 0.1778)
							(mid 0.239121 0.213721)
							(end 0.2032 0.2286)
						)
						(arc
							(start -0.2032 0.2286)
							(mid -0.239121 0.213721)
							(end -0.254 0.1778)
						)
					)
					(width 0)
					(fill yes)
				)
			)
		)
		(pad "2" smd custom
			(at 0 0.4572 180)
			(size 0.1143 0.1143)
			(layers "F.Cu" "F.Mask" "F.Paste")
			(net "GND")
			(options
				(clearance outline)
				(anchor circle)
			)
			(primitives
				(gr_poly
					(pts
						(arc
							(start -0.254 -0.1778)
							(mid -0.239121 -0.213721)
							(end -0.2032 -0.2286)
						)
						(arc
							(start 0.2032 -0.2286)
							(mid 0.239121 -0.213721)
							(end 0.254 -0.1778)
						)
						(arc
							(start 0.254 0.1778)
							(mid 0.239121 0.213721)
							(end 0.2032 0.2286)
						)
						(arc
							(start -0.2032 0.2286)
							(mid -0.239121 0.213721)
							(end -0.254 0.1778)
						)
					)
					(width 0)
					(fill yes)
				)
			)
		)
	)
	(footprint ""
		(layer "F.Cu")
		(at 120.0658 -62.357 -90)
		(property "Reference" "C98"
			(at 0 0 270)
			(layer "F.SilkS")
			(hide yes)
			(effects
				(font
					(size 1.27 1.27)
				)
			)
		)
		(property "Value" "SC1U6D3V2KX-GP"
			(at 1.1811 -2.7051 270)
			(unlocked yes)
			(layer "F.Fab")
			(hide yes)
			(effects
				(font
					(size 1.016 1.016)
					(thickness 0.1524)
				)
			)
		)
		(property "Device Type" "C402H22"
			(at 1.1811 -4.2291 270)
			(unlocked yes)
			(layer "F.Fab")
			(hide yes)
			(effects
				(font
					(size 1.016 1.016)
					(thickness 0.1524)
				)
			)
		)
		(duplicate_pad_numbers_are_jumpers no)
		(fp_rect
			(start -0.381 0.7366)
			(end 0.381 -0.7366)
			(stroke
				(width 0)
				(type default)
			)
			(fill no)
			(layer "F.CrtYd")
		)
		(fp_rect
			(start -0.381 0.7366)
			(end 0.381 -0.7366)
			(stroke
				(width 0)
				(type default)
			)
			(fill no)
			(layer "F.Fab")
		)
		(pad "1" smd custom
			(at 0 -0.4572 270)
			(size 0.1143 0.1143)
			(layers "F.Cu" "F.Mask" "F.Paste")
			(net "PV_VTT_DDR_A")
			(options
				(clearance outline)
				(anchor circle)
			)
			(primitives
				(gr_poly
					(pts
						(arc
							(start -0.254 -0.1778)
							(mid -0.239121 -0.213721)
							(end -0.2032 -0.2286)
						)
						(arc
							(start 0.2032 -0.2286)
							(mid 0.239121 -0.213721)
							(end 0.254 -0.1778)
						)
						(arc
							(start 0.254 0.1778)
							(mid 0.239121 0.213721)
							(end 0.2032 0.2286)
						)
						(arc
							(start -0.2032 0.2286)
							(mid -0.239121 0.213721)
							(end -0.254 0.1778)
						)
					)
					(width 0)
					(fill yes)
				)
			)
		)
		(pad "2" smd custom
			(at 0 0.4572 270)
			(size 0.1143 0.1143)
			(layers "F.Cu" "F.Mask" "F.Paste")
			(net "GND")
			(options
				(clearance outline)
				(anchor circle)
			)
			(primitives
				(gr_poly
					(pts
						(arc
							(start -0.254 -0.1778)
							(mid -0.239121 -0.213721)
							(end -0.2032 -0.2286)
						)
						(arc
							(start 0.2032 -0.2286)
							(mid 0.239121 -0.213721)
							(end 0.254 -0.1778)
						)
						(arc
							(start 0.254 0.1778)
							(mid 0.239121 0.213721)
							(end 0.2032 0.2286)
						)
						(arc
							(start -0.2032 0.2286)
							(mid -0.239121 0.213721)
							(end -0.254 0.1778)
						)
					)
					(width 0)
					(fill yes)
				)
			)
		)
	)
	(footprint ""
		(layer "F.Cu")
		(at 201.803 -21.717 180)
		(property "Reference" "PL7"
			(at 0 0 180)
			(layer "F.SilkS")
			(hide yes)
			(effects
				(font
					(size 1.27 1.27)
				)
			)
		)
		(property "Value" "BLM41PG600-GP"
			(at 0 -5.5372 180)
			(unlocked yes)
			(layer "F.Fab")
			(hide yes)
			(effects
				(font
					(size 1.016 1.016)
					(thickness 0.1524)
				)
			)
		)
		(property "Device Type" "L451616H71"
			(at 0 -7.0612 180)
			(unlocked yes)
			(layer "F.Fab")
			(hide yes)
			(effects
				(font
					(size 1.016 1.016)
					(thickness 0.1524)
				)
			)
		)
		(duplicate_pad_numbers_are_jumpers no)
		(fp_rect
			(start -1.0668 2.7559)
			(end 1.0668 -2.7559)
			(stroke
				(width 0)
				(type default)
			)
			(fill no)
			(layer "F.CrtYd")
		)
		(fp_rect
			(start -1.0668 2.7559)
			(end 1.0668 -2.7559)
			(stroke
				(width 0)
				(type default)
			)
			(fill no)
			(layer "F.Fab")
		)
		(pad "1" smd rect
			(at 0 -1.9558 180)
			(size 1.8796 1.3462)
			(layers "F.Cu" "F.Mask" "F.Paste")
			(net "P12V")
		)
		(pad "2" smd rect
			(at 0 1.9558 180)
			(size 1.8796 1.3462)
			(layers "F.Cu" "F.Mask" "F.Paste")
			(net "PVDDR_VIN")
		)
	)
	(footprint ""
		(layer "F.Cu")
		(at 33.147 -54.9656)
		(property "Reference" "PC23"
			(at 0 0 0)
			(layer "F.SilkS")
			(hide yes)
			(effects
				(font
					(size 1.27 1.27)
				)
			)
		)
		(property "Value" "SC10U25V5KX-GP"
			(at 0 -4.9022 0)
			(unlocked yes)
			(layer "F.Fab")
			(hide yes)
			(effects
				(font
					(size 1.016 1.016)
					(thickness 0.1524)
				)
			)
		)
		(property "Device Type" "C805H56"
			(at 0 -6.8072 0)
			(unlocked yes)
			(layer "F.Fab")
			(hide yes)
			(effects
				(font
					(size 1.016 1.016)
					(thickness 0.1524)
				)
			)
		)
		(duplicate_pad_numbers_are_jumpers no)
		(fp_line
			(start 0.6096 0)
			(end -0.6096 0)
			(stroke
				(width 0.3048)
				(type default)
			)
			(layer "F.SilkS")
		)
		(fp_poly
			(pts
				(xy -0.9017 1.4351) (xy 0.9017 1.4351) (xy 0.9017 -1.4351) (xy -0.9017 -1.4351)
			)
			(stroke
				(width 0)
				(type default)
			)
			(fill no)
			(layer "F.CrtYd")
		)
		(fp_poly
			(pts
				(xy 0.9017 1.4351) (xy 0.9017 -1.4351) (xy -0.9017 -1.4351) (xy -0.9017 1.4351)
			)
			(stroke
				(width 0)
				(type default)
			)
			(fill no)
			(layer "F.Fab")
		)
		(pad "1" smd rect
			(at 0 -0.8382)
			(size 1.5494 0.9398)
			(layers "F.Cu" "F.Mask" "F.Paste")
			(net "VR_FET_SW_P12V_PVCCP_PVNN")
		)
		(pad "2" smd rect
			(at 0 0.8382)
			(size 1.5494 0.9398)
			(layers "F.Cu" "F.Mask" "F.Paste")
			(net "GND")
		)
	)
	(footprint ""
		(layer "F.Cu")
		(at 153.035 -11.684 -90)
		(property "Reference" "C295"
			(at 0 0 270)
			(layer "F.SilkS")
			(hide yes)
			(effects
				(font
					(size 1.27 1.27)
				)
			)
		)
		(property "Value" "SCD1U16V2KX-3GP"
			(at 1.1811 -2.7051 270)
			(unlocked yes)
			(layer "F.Fab")
			(hide yes)
			(effects
				(font
					(size 1.016 1.016)
					(thickness 0.1524)
				)
			)
		)
		(property "Device Type" "C402H22"
			(at 1.1811 -4.2291 270)
			(unlocked yes)
			(layer "F.Fab")
			(hide yes)
			(effects
				(font
					(size 1.016 1.016)
					(thickness 0.1524)
				)
			)
		)
		(duplicate_pad_numbers_are_jumpers no)
		(fp_rect
			(start -0.381 0.7366)
			(end 0.381 -0.7366)
			(stroke
				(width 0)
				(type default)
			)
			(fill no)
			(layer "F.CrtYd")
		)
		(fp_rect
			(start -0.381 0.7366)
			(end 0.381 -0.7366)
			(stroke
				(width 0)
				(type default)
			)
			(fill no)
			(layer "F.Fab")
		)
		(pad "1" smd custom
			(at 0 -0.4572 270)
			(size 0.1143 0.1143)
			(layers "F.Cu" "F.Mask" "F.Paste")
			(net "DDR3_M_B_VREF_CA")
			(options
				(clearance outline)
				(anchor circle)
			)
			(primitives
				(gr_poly
					(pts
						(arc
							(start -0.254 -0.1778)
							(mid -0.239121 -0.213721)
							(end -0.2032 -0.2286)
						)
						(arc
							(start 0.2032 -0.2286)
							(mid 0.239121 -0.213721)
							(end 0.254 -0.1778)
						)
						(arc
							(start 0.254 0.1778)
							(mid 0.239121 0.213721)
							(end 0.2032 0.2286)
						)
						(arc
							(start -0.2032 0.2286)
							(mid -0.239121 0.213721)
							(end -0.254 0.1778)
						)
					)
					(width 0)
					(fill yes)
				)
			)
		)
		(pad "2" smd custom
			(at 0 0.4572 270)
			(size 0.1143 0.1143)
			(layers "F.Cu" "F.Mask" "F.Paste")
			(net "GND")
			(options
				(clearance outline)
				(anchor circle)
			)
			(primitives
				(gr_poly
					(pts
						(arc
							(start -0.254 -0.1778)
							(mid -0.239121 -0.213721)
							(end -0.2032 -0.2286)
						)
						(arc
							(start 0.2032 -0.2286)
							(mid 0.239121 -0.213721)
							(end 0.254 -0.1778)
						)
						(arc
							(start 0.254 0.1778)
							(mid 0.239121 0.213721)
							(end 0.2032 0.2286)
						)
						(arc
							(start -0.2032 0.2286)
							(mid -0.239121 0.213721)
							(end -0.254 0.1778)
						)
					)
					(width 0)
					(fill yes)
				)
			)
		)
	)
	(footprint ""
		(layer "F.Cu")
		(at 5.7658 -53.3654 90)
		(property "Reference" "R144"
			(at 0 0 90)
			(layer "F.SilkS")
			(hide yes)
			(effects
				(font
					(size 1.27 1.27)
				)
			)
		)
		(property "Value" "10KR2F-2-GP"
			(at 0.064008 -3.993896 90)
			(unlocked yes)
			(layer "F.Fab")
			(hide yes)
			(effects
				(font
					(size 1.016 1.016)
					(thickness 0.1524)
				)
			)
		)
		(property "Device Type" "R402H16"
			(at 0.064008 -5.517896 90)
			(unlocked yes)
			(layer "F.Fab")
			(hide yes)
			(effects
				(font
					(size 1.016 1.016)
					(thickness 0.1524)
				)
			)
		)
		(duplicate_pad_numbers_are_jumpers no)
		(fp_rect
			(start -0.381 0.8382)
			(end 0.381 -0.8382)
			(stroke
				(width 0)
				(type default)
			)
			(fill no)
			(layer "F.CrtYd")
		)
		(fp_rect
			(start -0.381 0.8382)
			(end 0.381 -0.8382)
			(stroke
				(width 0)
				(type default)
			)
			(fill no)
			(layer "F.Fab")
		)
		(pad "1" smd custom
			(at 0 -0.4318 90)
			(size 0.127 0.127)
			(layers "F.Cu" "F.Mask" "F.Paste")
			(net "PEDET_SEL")
			(options
				(clearance outline)
				(anchor circle)
			)
			(primitives
				(gr_poly
					(pts
						(arc
							(start -0.2032 -0.2794)
							(mid -0.239121 -0.264521)
							(end -0.254 -0.2286)
						)
						(arc
							(start -0.254 0.2286)
							(mid -0.239121 0.264521)
							(end -0.2032 0.2794)
						)
						(arc
							(start 0.2032 0.2794)
							(mid 0.239121 0.264521)
							(end 0.254 0.2286)
						)
						(arc
							(start 0.254 -0.2286)
							(mid 0.239121 -0.264521)
							(end 0.2032 -0.2794)
						)
					)
					(width 0)
					(fill yes)
				)
			)
		)
		(pad "2" smd custom
			(at 0 0.4318 90)
			(size 0.127 0.127)
			(layers "F.Cu" "F.Mask" "F.Paste")
			(net "GND")
			(options
				(clearance outline)
				(anchor circle)
			)
			(primitives
				(gr_poly
					(pts
						(arc
							(start -0.2032 -0.2794)
							(mid -0.239121 -0.264521)
							(end -0.254 -0.2286)
						)
						(arc
							(start -0.254 0.2286)
							(mid -0.239121 0.264521)
							(end -0.2032 0.2794)
						)
						(arc
							(start 0.2032 0.2794)
							(mid 0.239121 0.264521)
							(end 0.254 0.2286)
						)
						(arc
							(start 0.254 -0.2286)
							(mid 0.239121 -0.264521)
							(end 0.2032 -0.2794)
						)
					)
					(width 0)
					(fill yes)
				)
			)
		)
	)
)
